# T6G (Grand Teton) — schematic netlist excerpt (pin names and nets, part order shuffled) for the footprints in the layout excerpt that follows; sources: Cadence DE-HDL packaged netlist, KiCad conversion of 04192023_DAF0TMB3IC0_F0TG_MB_C_brd_V02_OCP.brd

PC103  Q_CAPP  220UF 4V 20% SPCAP  pkg SMLF  page 201 : A = PVDDCR_CPU1_P0 ; B = GND
C1094  Q_CAP  0.1UF 25V 10% X7R  pkg 0402  page 258 : A = P3V3_ADC128_2_VCC ; B = GND

(kicad_pcb
	(version 20260206)
	(generator "pcbnew")
	(generator_version "10.0")
	(general
		(thickness 1.6)
		(legacy_teardrops no)
	)
	(paper "A4")
	(title_block
		(title "04192023_DAF0TMB3IC0_F0TG_MB_C_brd_V02_OCP.brd")
		(comment 1 "Grand Teton / footprints 8089-8090 of 8354")
	)
	(layers
		(0 "F.Cu" signal "TOP")
		(4 "In1.Cu" signal "GND")
		(6 "In2.Cu" signal "IN1")
		(8 "In3.Cu" signal "GND1")
		(10 "In4.Cu" signal "IN2")
		(12 "In5.Cu" signal "GND2")
		(14 "In6.Cu" signal "IN3")
		(16 "In7.Cu" signal "GND3")
		(18 "In8.Cu" signal "VCC")
		(20 "In9.Cu" signal "VCC1")
		(22 "In10.Cu" signal "GND4")
		(24 "In11.Cu" signal "IN4")
		(26 "In12.Cu" signal "GND5")
		(28 "In13.Cu" signal "IN5")
		(30 "In14.Cu" signal "GND6")
		(32 "In15.Cu" signal "IN6")
		(34 "In16.Cu" signal "GND7")
		(2 "B.Cu" signal "BOTTOM")
		(9 "F.Adhes" user "F.Adhesive")
		(11 "B.Adhes" user "B.Adhesive")
		(13 "F.Paste" user "Package Geometry/Pastemask Top")
		(15 "B.Paste" user "Package Geometry/Pastemask Bottom")
		(5 "F.SilkS" user "Ref Des/Silkscreen Top")
		(7 "B.SilkS" user "Ref Des/Silkscreen Bottom")
		(1 "F.Mask" user "Board Geometry/Soldermask Top")
		(3 "B.Mask" user "Board Geometry/Soldermask Bottom")
		(17 "Dwgs.User" user "User.Drawings")
		(19 "Cmts.User" user "User.Comments")
		(21 "Eco1.User" user "User.Eco1")
		(23 "Eco2.User" user "User.Eco2")
		(25 "Edge.Cuts" user "Board Geometry/Outline")
		(27 "Margin" user)
		(31 "F.CrtYd" user "Package Geometry/Place Bound Top")
		(29 "B.CrtYd" user "Package Geometry/Place Bound Bottom")
		(35 "F.Fab" user "Ref Des/Assembly Top")
		(33 "B.Fab" user "Ref Des/Assembly Bottom")
	)
	(footprint ""
		(layer "B.Cu")
		(at 213.253066 -325.456296)
		(property "Reference" "C1094"
			(at 0 0 0)
			(layer "B.SilkS")
			(hide yes)
			(effects
				(font
					(size 1.27 1.27)
				)
				(justify mirror)
			)
		)
		(property "Value" ""
			(at 0 0 0)
			(layer "B.Fab")
			(effects
				(font
					(size 1.27 1.27)
				)
				(justify mirror)
			)
		)
		(duplicate_pad_numbers_are_jumpers no)
		(fp_line
			(start -0.7874 -0.4064)
			(end -0.7874 0.4064)
			(stroke
				(width 0.1524)
				(type default)
			)
			(layer "B.SilkS")
		)
		(fp_line
			(start -0.7874 0.4064)
			(end 0.7874 0.4064)
			(stroke
				(width 0.1524)
				(type default)
			)
			(layer "B.SilkS")
		)
		(fp_line
			(start 0.7874 -0.4064)
			(end -0.7874 -0.4064)
			(stroke
				(width 0.1524)
				(type default)
			)
			(layer "B.SilkS")
		)
		(fp_line
			(start 0.7874 0.4064)
			(end 0.7874 -0.4064)
			(stroke
				(width 0.1524)
				(type default)
			)
			(layer "B.SilkS")
		)
		(fp_line
			(start -0.67945 -0.3048)
			(end -0.67945 0.3048)
			(stroke
				(width 0.1)
				(type default)
			)
			(layer "B.Fab")
		)
		(fp_line
			(start -0.67945 0.3048)
			(end -0.120396 0.3048)
			(stroke
				(width 0.1)
				(type default)
			)
			(layer "B.Fab")
		)
		(fp_line
			(start -0.12065 -0.3048)
			(end -0.67945 -0.3048)
			(stroke
				(width 0.1)
				(type default)
			)
			(layer "B.Fab")
		)
		(fp_line
			(start -0.12065 -0.2794)
			(end -0.12065 -0.3048)
			(stroke
				(width 0.1)
				(type default)
			)
			(layer "B.Fab")
		)
		(fp_line
			(start -0.120396 0.2794)
			(end 0.12065 0.2794)
			(stroke
				(width 0.1)
				(type default)
			)
			(layer "B.Fab")
		)
		(fp_line
			(start -0.120396 0.3048)
			(end -0.120396 0.2794)
			(stroke
				(width 0.1)
				(type default)
			)
			(layer "B.Fab")
		)
		(fp_line
			(start 0.12065 -0.305054)
			(end 0.12065 -0.2794)
			(stroke
				(width 0.1)
				(type default)
			)
			(layer "B.Fab")
		)
		(fp_line
			(start 0.12065 -0.2794)
			(end -0.12065 -0.2794)
			(stroke
				(width 0.1)
				(type default)
			)
			(layer "B.Fab")
		)
		(fp_line
			(start 0.12065 0.2794)
			(end 0.12065 0.3048)
			(stroke
				(width 0.1)
				(type default)
			)
			(layer "B.Fab")
		)
		(fp_line
			(start 0.12065 0.3048)
			(end 0.67945 0.3048)
			(stroke
				(width 0.1)
				(type default)
			)
			(layer "B.Fab")
		)
		(fp_line
			(start 0.67945 -0.305054)
			(end 0.12065 -0.305054)
			(stroke
				(width 0.1)
				(type default)
			)
			(layer "B.Fab")
		)
		(fp_line
			(start 0.67945 0.3048)
			(end 0.67945 -0.305054)
			(stroke
				(width 0.1)
				(type default)
			)
			(layer "B.Fab")
		)
		(pad "1" smd circle
			(at 0.40005 0 180)
			(size 0 0)
			(layers "B.Cu" "B.Mask" "B.Paste")
			(net "P3V3_ADC128_2_VCC")
		)
		(pad "2" smd circle
			(at -0.40005 0 180)
			(size 0 0)
			(layers "B.Cu" "B.Mask" "B.Paste")
			(net "GND")
		)
	)
	(footprint ""
		(layer "B.Cu")
		(at 334.69707 -328.219054 -90)
		(property "Reference" "PC103"
			(at 10.084054 -0.93726 270)
			(unlocked yes)
			(layer "B.SilkS")
			(effects
				(font
					(size 0.7874 0.5842)
					(thickness 0.1524)
				)
				(justify left mirror)
			)
		)
		(property "Value" ""
			(at 0 0 90)
			(layer "B.Fab")
			(effects
				(font
					(size 1.27 1.27)
				)
				(justify mirror)
			)
		)
		(duplicate_pad_numbers_are_jumpers no)
		(fp_line
			(start -4.533392 2.249932)
			(end 4.533392 2.249932)
			(stroke
				(width 0.1524)
				(type default)
			)
			(layer "B.SilkS")
		)
		(fp_line
			(start 4.533392 2.249932)
			(end 4.533392 -2.249932)
			(stroke
				(width 0.1524)
				(type default)
			)
			(layer "B.SilkS")
		)
		(fp_line
			(start -4.533392 -2.249932)
			(end -4.533392 2.249932)
			(stroke
				(width 0.1524)
				(type default)
			)
			(layer "B.SilkS")
		)
		(fp_line
			(start 4.533392 -2.249932)
			(end -4.533392 -2.249932)
			(stroke
				(width 0.1524)
				(type default)
			)
			(layer "B.SilkS")
		)
		(fp_rect
			(start 5.39242 2.326132)
			(end 4.533392 -2.326132)
			(stroke
				(width 0)
				(type default)
			)
			(fill yes)
			(layer "B.SilkS")
		)
		(fp_line
			(start -3.750056 2.249932)
			(end 3.750056 2.249932)
			(stroke
				(width 0.1)
				(type default)
			)
			(layer "B.Fab")
		)
		(fp_line
			(start 3.750056 2.249932)
			(end 3.750056 -2.249932)
			(stroke
				(width 0.1)
				(type default)
			)
			(layer "B.Fab")
		)
		(fp_line
			(start -3.750056 -2.249932)
			(end -3.750056 2.249932)
			(stroke
				(width 0.1)
				(type default)
			)
			(layer "B.Fab")
		)
		(fp_line
			(start 3.750056 -2.249932)
			(end -3.750056 -2.249932)
			(stroke
				(width 0.1)
				(type default)
			)
			(layer "B.Fab")
		)
		(fp_text user "+"
			(at 6.381242 0.548386 180)
			(unlocked yes)
			(layer "B.SilkS")
			(effects
				(font
					(size 1.905 1.4224)
					(thickness 0.1524)
				)
				(justify left mirror)
			)
		)
		(fp_text user "-"
			(at -4.8514 -0.14605 270)
			(unlocked yes)
			(layer "B.SilkS")
			(effects
				(font
					(size 1.905 1.4224)
					(thickness 0.1524)
				)
				(justify left mirror)
			)
		)
		(fp_text user "+"
			(at 6.322314 0.786384 180)
			(unlocked yes)
			(layer "B.Fab")
			(effects
				(font
					(size 1.905 1.4224)
					(thickness 0.1524)
				)
				(justify left mirror)
			)
		)
		(fp_text user "-"
			(at -4.8514 -0.14605 270)
			(unlocked yes)
			(layer "B.Fab")
			(effects
				(font
					(size 1.905 1.4224)
					(thickness 0.1524)
				)
				(justify left mirror)
			)
		)
		(pad "1" smd rect
			(at 3.199892 0 90)
			(size 2.413 2.8194)
			(layers "B.Cu" "B.Mask" "B.Paste")
			(net "PVDDCR_CPU1_P0")
		)
		(pad "2" smd rect
			(at -3.199892 0 90)
			(size 2.413 2.8194)
			(layers "B.Cu" "B.Mask" "B.Paste")
			(net "GND")
		)
	)
)
